# BASEBOARD_FAB2 (Tioga Pass) — schematic netlist excerpt (pin names and nets, part order shuffled) for the footprints in the layout excerpt that follows; sources: Cadence DE-HDL packaged netlist, KiCad conversion of Wiwynn_Tioga_Pass_MB.brd

C7B9  CAP  1000PF 50V 10% EMPTY  pkg 0402LF  page 232 : A = FM_PVPP_CPU0_EN ; B = AGND_PVPP_DEF
Y7C1  CRYSTAL  48.000MHZ IC  pkg 2013  page 114 : A = XTAL_PCH_48M_IN ; B = XTAL_PCH_48M_OUT
R1G14  RES  2 1.0% CHIP  pkg 0402  page 100 : A = M_J_CPU_VREF ; B = M_J_VREF

(kicad_pcb
	(version 20260206)
	(generator "pcbnew")
	(generator_version "10.0")
	(general
		(thickness 1.6)
		(legacy_teardrops no)
	)
	(paper "A4")
	(title_block
		(title "Wiwynn_Tioga_Pass_MB.brd")
		(comment 1 "Tioga Pass / footprints 22-24 of 4770")
	)
	(layers
		(0 "F.Cu" signal "TOP")
		(4 "In1.Cu" signal "L2GND")
		(6 "In2.Cu" signal "L3")
		(8 "In3.Cu" signal "L4GND")
		(10 "In4.Cu" signal "L5")
		(12 "In5.Cu" signal "L6GND")
		(14 "In6.Cu" signal "L7VCC")
		(16 "In7.Cu" signal "L8VCC")
		(18 "In8.Cu" signal "L9GND")
		(20 "In9.Cu" signal "L10")
		(22 "In10.Cu" signal "L11GND")
		(24 "In11.Cu" signal "L12")
		(26 "In12.Cu" signal "L13GND")
		(2 "B.Cu" signal "BOTTOM")
		(9 "F.Adhes" user "F.Adhesive")
		(11 "B.Adhes" user "B.Adhesive")
		(13 "F.Paste" user "Package Geometry/Pastemask Top")
		(15 "B.Paste" user "Package Geometry/Pastemask Bottom")
		(5 "F.SilkS" user "Ref Des/Silkscreen Top")
		(7 "B.SilkS" user "Ref Des/Silkscreen Bottom")
		(1 "F.Mask" user "Board Geometry/Soldermask Top")
		(3 "B.Mask" user "Board Geometry/Soldermask Bottom")
		(17 "Dwgs.User" user "User.Drawings")
		(19 "Cmts.User" user "User.Comments")
		(21 "Eco1.User" user "User.Eco1")
		(23 "Eco2.User" user "User.Eco2")
		(25 "Edge.Cuts" user "Board Geometry/Outline")
		(27 "Margin" user)
		(31 "F.CrtYd" user "Package Geometry/Place Bound Top")
		(29 "B.CrtYd" user "Package Geometry/Place Bound Bottom")
		(35 "F.Fab" user "Ref Des/Assembly Top")
		(33 "B.Fab" user "Ref Des/Assembly Bottom")
	)
	(footprint ""
		(layer "F.Cu")
		(at 339.1154 -128.3208)
		(property "Reference" "C7B9"
			(at 0 0 0)
			(layer "F.SilkS")
			(hide yes)
			(effects
				(font
					(size 1.27 1.27)
				)
			)
		)
		(property "Value" ""
			(at 0 0 0)
			(layer "F.Fab")
			(effects
				(font
					(size 1.27 1.27)
				)
			)
		)
		(duplicate_pad_numbers_are_jumpers no)
		(fp_poly
			(pts
				(xy 0.3048 -0.1016) (xy 0.3048 0.9906) (xy -0.3048 0.9906) (xy -0.3048 -0.1016)
			)
			(stroke
				(width 0)
				(type default)
			)
			(fill no)
			(layer "F.CrtYd")
		)
		(fp_line
			(start -0.3048 -0.1016)
			(end -0.3048 0.9906)
			(stroke
				(width 0.1)
				(type default)
			)
			(layer "F.Fab")
		)
		(fp_line
			(start -0.3048 0.9906)
			(end 0.3048 0.9906)
			(stroke
				(width 0.1)
				(type default)
			)
			(layer "F.Fab")
		)
		(fp_line
			(start 0.3048 -0.1016)
			(end -0.3048 -0.1016)
			(stroke
				(width 0.1)
				(type default)
			)
			(layer "F.Fab")
		)
		(fp_line
			(start 0.3048 0.9906)
			(end 0.3048 -0.1016)
			(stroke
				(width 0.1)
				(type default)
			)
			(layer "F.Fab")
		)
		(pad "1" smd rect
			(at 0 0)
			(size 0.508 0.508)
			(layers "F.Cu" "F.Mask" "F.Paste")
			(net "FM_PVPP_CPU0_EN")
		)
		(pad "2" smd rect
			(at 0 0.889)
			(size 0.508 0.508)
			(layers "F.Cu" "F.Mask" "F.Paste")
			(net "AGND_PVPP_DEF")
		)
		(zone
			(layer "F.Cu")
			(hatch none 0.5)
			(connect_pads
				(clearance 0)
			)
			(min_thickness 0.25)
			(keepout
				(tracks allowed)
				(vias not_allowed)
				(pads allowed)
				(copperpour not_allowed)
				(footprints allowed)
			)
			(placement
				(enabled no)
				(sheetname "")
			)
			(fill
				(thermal_gap 0.5)
				(thermal_bridge_width 0.5)
				(island_removal_mode 0)
			)
			(polygon
				(pts
					(xy 338.8614 -128.0668) (xy 339.3694 -128.0668) (xy 339.3694 -127.6858) (xy 338.8614 -127.6858)
				)
			)
		)
		(zone
			(layer "F.Cu")
			(hatch none 0.5)
			(connect_pads
				(clearance 0)
			)
			(min_thickness 0.25)
			(keepout
				(tracks not_allowed)
				(vias allowed)
				(pads allowed)
				(copperpour not_allowed)
				(footprints allowed)
			)
			(placement
				(enabled no)
				(sheetname "")
			)
			(fill
				(thermal_gap 0.5)
				(thermal_bridge_width 0.5)
				(island_removal_mode 0)
			)
			(polygon
				(pts
					(xy 338.8614 -127.6858) (xy 339.3694 -127.6858) (xy 339.3694 -128.0668) (xy 338.8614 -128.0668)
				)
			)
		)
	)
	(footprint ""
		(layer "F.Cu")
		(at 27.813 -3.766312)
		(property "Reference" "R1G14"
			(at 0 0 0)
			(layer "F.SilkS")
			(hide yes)
			(effects
				(font
					(size 1.27 1.27)
				)
			)
		)
		(property "Value" ""
			(at 0 0 0)
			(layer "F.Fab")
			(effects
				(font
					(size 1.27 1.27)
				)
			)
		)
		(duplicate_pad_numbers_are_jumpers no)
		(fp_poly
			(pts
				(xy -0.2794 -0.1016) (xy 0.2794 -0.1016) (xy 0.2794 0.9906) (xy -0.2794 0.9906)
			)
			(stroke
				(width 0)
				(type default)
			)
			(fill no)
			(layer "F.CrtYd")
		)
		(fp_line
			(start -0.2794 -0.1016)
			(end -0.2794 0.9906)
			(stroke
				(width 0.1)
				(type default)
			)
			(layer "F.Fab")
		)
		(fp_line
			(start -0.2794 0.9906)
			(end 0.2794 0.9906)
			(stroke
				(width 0.1)
				(type default)
			)
			(layer "F.Fab")
		)
		(fp_line
			(start 0.2794 -0.1016)
			(end -0.2794 -0.1016)
			(stroke
				(width 0.1)
				(type default)
			)
			(layer "F.Fab")
		)
		(fp_line
			(start 0.2794 0.9906)
			(end 0.2794 -0.1016)
			(stroke
				(width 0.1)
				(type default)
			)
			(layer "F.Fab")
		)
		(pad "1" smd rect
			(at 0 0)
			(size 0.508 0.508)
			(layers "F.Cu" "F.Mask" "F.Paste")
			(net "M_J_CPU_VREF")
		)
		(pad "2" smd rect
			(at 0 0.889)
			(size 0.508 0.508)
			(layers "F.Cu" "F.Mask" "F.Paste")
			(net "M_J_VREF")
		)
		(zone
			(layer "F.Cu")
			(hatch none 0.5)
			(connect_pads
				(clearance 0)
			)
			(min_thickness 0.25)
			(keepout
				(tracks allowed)
				(vias not_allowed)
				(pads allowed)
				(copperpour not_allowed)
				(footprints allowed)
			)
			(placement
				(enabled no)
				(sheetname "")
			)
			(fill
				(thermal_gap 0.5)
				(thermal_bridge_width 0.5)
				(island_removal_mode 0)
			)
			(polygon
				(pts
					(xy 27.559 -3.512312) (xy 28.067 -3.512312) (xy 28.067 -3.131312) (xy 27.559 -3.131312)
				)
			)
		)
		(zone
			(layer "F.Cu")
			(hatch none 0.5)
			(connect_pads
				(clearance 0)
			)
			(min_thickness 0.25)
			(keepout
				(tracks not_allowed)
				(vias allowed)
				(pads allowed)
				(copperpour not_allowed)
				(footprints allowed)
			)
			(placement
				(enabled no)
				(sheetname "")
			)
			(fill
				(thermal_gap 0.5)
				(thermal_bridge_width 0.5)
				(island_removal_mode 0)
			)
			(polygon
				(pts
					(xy 27.559 -3.131312) (xy 28.067 -3.131312) (xy 28.067 -3.512312) (xy 27.559 -3.512312)
				)
			)
		)
	)
	(footprint ""
		(layer "F.Cu")
		(at 365.506 -108.614972)
		(property "Reference" "Y7C1"
			(at -1.11633 2.794 90)
			(unlocked yes)
			(layer "F.SilkS")
			(effects
				(font
					(size 0.7874 0.5842)
					(thickness 0.1524)
				)
				(justify left)
			)
		)
		(property "Value" ""
			(at 0 0 0)
			(layer "F.Fab")
			(effects
				(font
					(size 1.27 1.27)
				)
			)
		)
		(duplicate_pad_numbers_are_jumpers no)
		(fp_circle
			(center -1.049782 -0.44323)
			(end -0.922782 -0.44323)
			(stroke
				(width 0.254)
				(type default)
			)
			(fill no)
			(layer "F.SilkS")
		)
		(fp_rect
			(start -0.499872 2.70002)
			(end 2.100072 -0.599948)
			(stroke
				(width 0)
				(type default)
			)
			(fill no)
			(layer "F.CrtYd")
		)
		(fp_line
			(start -0.499872 -0.599948)
			(end 2.100072 -0.599948)
			(stroke
				(width 0.1)
				(type default)
			)
			(layer "F.Fab")
		)
		(fp_line
			(start -0.499872 2.70002)
			(end -0.499872 -0.599948)
			(stroke
				(width 0.1)
				(type default)
			)
			(layer "F.Fab")
		)
		(fp_line
			(start 2.100072 -0.599948)
			(end 2.100072 2.70002)
			(stroke
				(width 0.1)
				(type default)
			)
			(layer "F.Fab")
		)
		(fp_line
			(start 2.100072 2.70002)
			(end -0.499872 2.70002)
			(stroke
				(width 0.1)
				(type default)
			)
			(layer "F.Fab")
		)
		(fp_circle
			(center -1.049782 -0.44323)
			(end -0.922782 -0.44323)
			(stroke
				(width 0.254)
				(type default)
			)
			(fill no)
			(layer "F.Fab")
		)
		(pad "1" smd rect
			(at 0 0)
			(size 1.0414 1.143)
			(layers "F.Cu" "F.Mask" "F.Paste")
			(net "XTAL_PCH_48M_IN")
		)
		(pad "2" smd rect
			(at 0 2.100072)
			(size 1.0414 1.143)
			(layers "F.Cu" "F.Mask" "F.Paste")
			(net "GND")
		)
		(pad "3" smd rect
			(at 1.6002 2.100072)
			(size 1.0414 1.143)
			(layers "F.Cu" "F.Mask" "F.Paste")
			(net "XTAL_PCH_48M_OUT")
		)
		(pad "4" smd rect
			(at 1.6002 0)
			(size 1.0414 1.143)
			(layers "F.Cu" "F.Mask" "F.Paste")
			(net "GND")
		)
	)
)
